# S9S_MB_2U (Grand Teton) — schematic netlist excerpt (pin names and nets, part order shuffled) for the footprints in the layout excerpt that follows; sources: Cadence DE-HDL packaged netlist, KiCad conversion of 03242023_DA0F0TMBIJ0_F0T_Motherboard_J_brd_V01_OCP.brd

R4274  Q_RES  1K 1% EMPTY  pkg 0402LF  page 169 : A = FM_USB3_1_FGB ; B = GND
C71  Q_CAP  10UF 6.3V 20% X6S  pkg C0402  page 68 : A = P3V3_AUX ; B = GND

(kicad_pcb
	(version 20260206)
	(generator "pcbnew")
	(generator_version "10.0")
	(general
		(thickness 1.6)
		(legacy_teardrops no)
	)
	(paper "A4")
	(title_block
		(title "03242023_DA0F0TMBIJ0_F0T_Motherboard_J_brd_V01_OCP.brd")
		(comment 1 "Grand Teton / footprints 5399-5400 of 6105")
	)
	(layers
		(0 "F.Cu" signal "TOP")
		(4 "In1.Cu" signal "GND")
		(6 "In2.Cu" signal "IN1")
		(8 "In3.Cu" signal "GND1")
		(10 "In4.Cu" signal "IN2")
		(12 "In5.Cu" signal "GND2")
		(14 "In6.Cu" signal "IN3")
		(16 "In7.Cu" signal "GND3")
		(18 "In8.Cu" signal "VCC")
		(20 "In9.Cu" signal "VCC1")
		(22 "In10.Cu" signal "GND4")
		(24 "In11.Cu" signal "IN4")
		(26 "In12.Cu" signal "GND5")
		(28 "In13.Cu" signal "IN5")
		(30 "In14.Cu" signal "GND6")
		(32 "In15.Cu" signal "IN6")
		(34 "In16.Cu" signal "GND7")
		(2 "B.Cu" signal "BOTTOM")
		(9 "F.Adhes" user "F.Adhesive")
		(11 "B.Adhes" user "B.Adhesive")
		(13 "F.Paste" user "Package Geometry/Pastemask Top")
		(15 "B.Paste" user "Package Geometry/Pastemask Bottom")
		(5 "F.SilkS" user "Ref Des/Silkscreen Top")
		(7 "B.SilkS" user "Ref Des/Silkscreen Bottom")
		(1 "F.Mask" user "Board Geometry/Soldermask Top")
		(3 "B.Mask" user "Board Geometry/Soldermask Bottom")
		(17 "Dwgs.User" user "User.Drawings")
		(19 "Cmts.User" user "User.Comments")
		(21 "Eco1.User" user "User.Eco1")
		(23 "Eco2.User" user "User.Eco2")
		(25 "Edge.Cuts" user "Board Geometry/Outline")
		(27 "Margin" user)
		(31 "F.CrtYd" user "Package Geometry/Place Bound Top")
		(29 "B.CrtYd" user "Package Geometry/Place Bound Bottom")
		(35 "F.Fab" user "Ref Des/Assembly Top")
		(33 "B.Fab" user "Ref Des/Assembly Bottom")
	)
	(footprint ""
		(layer "B.Cu")
		(at 104.786938 -236.00791 180)
		(property "Reference" "C71"
			(at 0 0 0)
			(layer "B.SilkS")
			(hide yes)
			(effects
				(font
					(size 1.27 1.27)
				)
				(justify mirror)
			)
		)
		(property "Value" ""
			(at 0 0 0)
			(layer "B.Fab")
			(effects
				(font
					(size 1.27 1.27)
				)
				(justify mirror)
			)
		)
		(duplicate_pad_numbers_are_jumpers no)
		(fp_line
			(start 0.7874 0.4064)
			(end 0.7874 -0.4064)
			(stroke
				(width 0.1524)
				(type default)
			)
			(layer "B.SilkS")
		)
		(fp_line
			(start 0.7874 -0.4064)
			(end -0.7874 -0.4064)
			(stroke
				(width 0.1524)
				(type default)
			)
			(layer "B.SilkS")
		)
		(fp_line
			(start -0.7874 0.4064)
			(end 0.7874 0.4064)
			(stroke
				(width 0.1524)
				(type default)
			)
			(layer "B.SilkS")
		)
		(fp_line
			(start -0.7874 -0.4064)
			(end -0.7874 0.4064)
			(stroke
				(width 0.1524)
				(type default)
			)
			(layer "B.SilkS")
		)
		(fp_line
			(start 0.67945 0.3048)
			(end 0.67945 -0.305054)
			(stroke
				(width 0.1)
				(type default)
			)
			(layer "B.Fab")
		)
		(fp_line
			(start 0.67945 -0.305054)
			(end 0.12065 -0.305054)
			(stroke
				(width 0.1)
				(type default)
			)
			(layer "B.Fab")
		)
		(fp_line
			(start 0.12065 0.3048)
			(end 0.67945 0.3048)
			(stroke
				(width 0.1)
				(type default)
			)
			(layer "B.Fab")
		)
		(fp_line
			(start 0.12065 0.2794)
			(end 0.12065 0.3048)
			(stroke
				(width 0.1)
				(type default)
			)
			(layer "B.Fab")
		)
		(fp_line
			(start 0.12065 -0.2794)
			(end -0.12065 -0.2794)
			(stroke
				(width 0.1)
				(type default)
			)
			(layer "B.Fab")
		)
		(fp_line
			(start 0.12065 -0.305054)
			(end 0.12065 -0.2794)
			(stroke
				(width 0.1)
				(type default)
			)
			(layer "B.Fab")
		)
		(fp_line
			(start -0.120396 0.3048)
			(end -0.120396 0.2794)
			(stroke
				(width 0.1)
				(type default)
			)
			(layer "B.Fab")
		)
		(fp_line
			(start -0.120396 0.2794)
			(end 0.12065 0.2794)
			(stroke
				(width 0.1)
				(type default)
			)
			(layer "B.Fab")
		)
		(fp_line
			(start -0.12065 -0.2794)
			(end -0.12065 -0.3048)
			(stroke
				(width 0.1)
				(type default)
			)
			(layer "B.Fab")
		)
		(fp_line
			(start -0.12065 -0.3048)
			(end -0.67945 -0.3048)
			(stroke
				(width 0.1)
				(type default)
			)
			(layer "B.Fab")
		)
		(fp_line
			(start -0.67945 0.3048)
			(end -0.120396 0.3048)
			(stroke
				(width 0.1)
				(type default)
			)
			(layer "B.Fab")
		)
		(fp_line
			(start -0.67945 -0.3048)
			(end -0.67945 0.3048)
			(stroke
				(width 0.1)
				(type default)
			)
			(layer "B.Fab")
		)
		(pad "1" smd circle
			(at 0.40005 0)
			(size 0 0)
			(layers "B.Cu" "B.Mask" "B.Paste")
			(net "P3V3_AUX")
		)
		(pad "2" smd circle
			(at -0.40005 0)
			(size 0 0)
			(layers "B.Cu" "B.Mask" "B.Paste")
			(net "GND")
		)
	)
	(footprint ""
		(layer "B.Cu")
		(at 128.86944 -36.751768 90)
		(property "Reference" "R4274"
			(at 0 0 90)
			(layer "B.SilkS")
			(hide yes)
			(effects
				(font
					(size 1.27 1.27)
				)
				(justify mirror)
			)
		)
		(property "Value" ""
			(at 0 0 90)
			(layer "B.Fab")
			(effects
				(font
					(size 1.27 1.27)
				)
				(justify mirror)
			)
		)
		(duplicate_pad_numbers_are_jumpers no)
		(fp_line
			(start 0.7874 -0.4064)
			(end -0.7874 -0.4064)
			(stroke
				(width 0.1524)
				(type default)
			)
			(layer "B.SilkS")
		)
		(fp_line
			(start -0.7874 -0.4064)
			(end -0.7874 0.4064)
			(stroke
				(width 0.1524)
				(type default)
			)
			(layer "B.SilkS")
		)
		(fp_line
			(start 0.7874 0.4064)
			(end 0.7874 -0.4064)
			(stroke
				(width 0.1524)
				(type default)
			)
			(layer "B.SilkS")
		)
		(fp_line
			(start -0.7874 0.4064)
			(end 0.7874 0.4064)
			(stroke
				(width 0.1524)
				(type default)
			)
			(layer "B.SilkS")
		)
		(fp_line
			(start 0.67945 -0.305054)
			(end 0.12065 -0.305054)
			(stroke
				(width 0.1)
				(type default)
			)
			(layer "B.Fab")
		)
		(fp_line
			(start 0.12065 -0.305054)
			(end 0.12065 -0.2794)
			(stroke
				(width 0.1)
				(type default)
			)
			(layer "B.Fab")
		)
		(fp_line
			(start -0.12065 -0.3048)
			(end -0.67945 -0.3048)
			(stroke
				(width 0.1)
				(type default)
			)
			(layer "B.Fab")
		)
		(fp_line
			(start -0.67945 -0.3048)
			(end -0.67945 0.3048)
			(stroke
				(width 0.1)
				(type default)
			)
			(layer "B.Fab")
		)
		(fp_line
			(start 0.12065 -0.2794)
			(end -0.12065 -0.2794)
			(stroke
				(width 0.1)
				(type default)
			)
			(layer "B.Fab")
		)
		(fp_line
			(start -0.12065 -0.2794)
			(end -0.12065 -0.3048)
			(stroke
				(width 0.1)
				(type default)
			)
			(layer "B.Fab")
		)
		(fp_line
			(start 0.12065 0.2794)
			(end 0.12065 0.3048)
			(stroke
				(width 0.1)
				(type default)
			)
			(layer "B.Fab")
		)
		(fp_line
			(start -0.120396 0.2794)
			(end 0.12065 0.2794)
			(stroke
				(width 0.1)
				(type default)
			)
			(layer "B.Fab")
		)
		(fp_line
			(start 0.67945 0.3048)
			(end 0.67945 -0.305054)
			(stroke
				(width 0.1)
				(type default)
			)
			(layer "B.Fab")
		)
		(fp_line
			(start 0.12065 0.3048)
			(end 0.67945 0.3048)
			(stroke
				(width 0.1)
				(type default)
			)
			(layer "B.Fab")
		)
		(fp_line
			(start -0.120396 0.3048)
			(end -0.120396 0.2794)
			(stroke
				(width 0.1)
				(type default)
			)
			(layer "B.Fab")
		)
		(fp_line
			(start -0.67945 0.3048)
			(end -0.120396 0.3048)
			(stroke
				(width 0.1)
				(type default)
			)
			(layer "B.Fab")
		)
		(pad "1" smd circle
			(at 0.40005 0 270)
			(size 0 0)
			(layers "B.Cu" "B.Mask" "B.Paste")
			(net "FM_USB3_1_FGB")
		)
		(pad "2" smd circle
			(at -0.40005 0 270)
			(size 0 0)
			(layers "B.Cu" "B.Mask" "B.Paste")
			(net "GND")
		)
	)
)
